(kicad_pcb
	(version 20260206)
	(generator "pcbnew")
	(generator_version "10.0")
	(general
		(thickness 1.6)
		(legacy_teardrops no)
	)
	(paper "A4")
	(title_block
		(title "03242023_DA0F0TMBIJ0_F0T_Motherboard_J_brd_V01_OCP.brd")
		(comment 1 "Grand Teton / footprints 3096-3102 of 6105")
	)
	(layers
		(0 "F.Cu" signal "TOP")
		(4 "In1.Cu" signal "GND")
		(6 "In2.Cu" signal "IN1")
		(8 "In3.Cu" signal "GND1")
		(10 "In4.Cu" signal "IN2")
		(12 "In5.Cu" signal "GND2")
		(14 "In6.Cu" signal "IN3")
		(16 "In7.Cu" signal "GND3")
		(18 "In8.Cu" signal "VCC")
		(20 "In9.Cu" signal "VCC1")
		(22 "In10.Cu" signal "GND4")
		(24 "In11.Cu" signal "IN4")
		(26 "In12.Cu" signal "GND5")
		(28 "In13.Cu" signal "IN5")
		(30 "In14.Cu" signal "GND6")
		(32 "In15.Cu" signal "IN6")
		(34 "In16.Cu" signal "GND7")
		(2 "B.Cu" signal "BOTTOM")
		(9 "F.Adhes" user "F.Adhesive")
		(11 "B.Adhes" user "B.Adhesive")
		(13 "F.Paste" user "Package Geometry/Pastemask Top")
		(15 "B.Paste" user "Package Geometry/Pastemask Bottom")
		(5 "F.SilkS" user "Ref Des/Silkscreen Top")
		(7 "B.SilkS" user "Ref Des/Silkscreen Bottom")
		(1 "F.Mask" user "Board Geometry/Soldermask Top")
		(3 "B.Mask" user "Board Geometry/Soldermask Bottom")
		(17 "Dwgs.User" user "User.Drawings")
		(19 "Cmts.User" user "User.Comments")
		(21 "Eco1.User" user "User.Eco1")
		(23 "Eco2.User" user "User.Eco2")
		(25 "Edge.Cuts" user "Board Geometry/Outline")
		(27 "Margin" user)
		(31 "F.CrtYd" user "Package Geometry/Place Bound Top")
		(29 "B.CrtYd" user "Package Geometry/Place Bound Bottom")
		(35 "F.Fab" user "Ref Des/Assembly Top")
		(33 "B.Fab" user "Ref Des/Assembly Bottom")
	)
	(footprint ""
		(layer "F.Cu")
		(at 36.605718 -353.75723)
		(property "Reference" "PR704"
			(at 0 0 0)
			(layer "F.SilkS")
			(hide yes)
			(effects
				(font
					(size 1.27 1.27)
				)
			)
		)
		(property "Value" ""
			(at 0 0 0)
			(layer "F.Fab")
			(effects
				(font
					(size 1.27 1.27)
				)
			)
		)
		(duplicate_pad_numbers_are_jumpers no)
		(fp_line
			(start -0.7874 -0.4064)
			(end 0.7874 -0.4064)
			(stroke
				(width 0.1524)
				(type default)
			)
			(layer "F.SilkS")
		)
		(fp_line
			(start -0.7874 0.4064)
			(end -0.7874 -0.4064)
			(stroke
				(width 0.1524)
				(type default)
			)
			(layer "F.SilkS")
		)
		(fp_line
			(start 0.7874 -0.4064)
			(end 0.7874 0.4064)
			(stroke
				(width 0.1524)
				(type default)
			)
			(layer "F.SilkS")
		)
		(fp_line
			(start 0.7874 0.4064)
			(end -0.7874 0.4064)
			(stroke
				(width 0.1524)
				(type default)
			)
			(layer "F.SilkS")
		)
		(fp_line
			(start -0.67945 -0.305054)
			(end -0.12065 -0.305054)
			(stroke
				(width 0.1)
				(type default)
			)
			(layer "F.Fab")
		)
		(fp_line
			(start -0.67945 0.3048)
			(end -0.67945 -0.305054)
			(stroke
				(width 0.1)
				(type default)
			)
			(layer "F.Fab")
		)
		(fp_line
			(start -0.12065 -0.305054)
			(end -0.12065 -0.2794)
			(stroke
				(width 0.1)
				(type default)
			)
			(layer "F.Fab")
		)
		(fp_line
			(start -0.12065 -0.2794)
			(end 0.12065 -0.2794)
			(stroke
				(width 0.1)
				(type default)
			)
			(layer "F.Fab")
		)
		(fp_line
			(start -0.12065 0.2794)
			(end -0.12065 0.3048)
			(stroke
				(width 0.1)
				(type default)
			)
			(layer "F.Fab")
		)
		(fp_line
			(start -0.12065 0.3048)
			(end -0.67945 0.3048)
			(stroke
				(width 0.1)
				(type default)
			)
			(layer "F.Fab")
		)
		(fp_line
			(start 0.120396 0.2794)
			(end -0.12065 0.2794)
			(stroke
				(width 0.1)
				(type default)
			)
			(layer "F.Fab")
		)
		(fp_line
			(start 0.120396 0.3048)
			(end 0.120396 0.2794)
			(stroke
				(width 0.1)
				(type default)
			)
			(layer "F.Fab")
		)
		(fp_line
			(start 0.12065 -0.3048)
			(end 0.67945 -0.3048)
			(stroke
				(width 0.1)
				(type default)
			)
			(layer "F.Fab")
		)
		(fp_line
			(start 0.12065 -0.2794)
			(end 0.12065 -0.3048)
			(stroke
				(width 0.1)
				(type default)
			)
			(layer "F.Fab")
		)
		(fp_line
			(start 0.67945 -0.3048)
			(end 0.67945 0.3048)
			(stroke
				(width 0.1)
				(type default)
			)
			(layer "F.Fab")
		)
		(fp_line
			(start 0.67945 0.3048)
			(end 0.120396 0.3048)
			(stroke
				(width 0.1)
				(type default)
			)
			(layer "F.Fab")
		)
		(pad "1" smd circle
			(at -0.40005 0)
			(size 0 0)
			(layers "F.Cu" "F.Mask" "F.Paste")
			(net "P3V3")
		)
		(pad "2" smd circle
			(at 0.40005 0)
			(size 0 0)
			(layers "F.Cu" "F.Mask" "F.Paste")
			(net "PVCCFA_EHV_FIVRA_CPU1_PVCC2")
		)
	)
	(footprint ""
		(layer "F.Cu")
		(at 46.350428 -102.888034)
		(property "Reference" "C1757"
			(at 0 0 0)
			(layer "F.SilkS")
			(hide yes)
			(effects
				(font
					(size 1.27 1.27)
				)
			)
		)
		(property "Value" ""
			(at 0 0 0)
			(layer "F.Fab")
			(effects
				(font
					(size 1.27 1.27)
				)
			)
		)
		(duplicate_pad_numbers_are_jumpers no)
		(fp_line
			(start -0.7874 -0.4064)
			(end 0.7874 -0.4064)
			(stroke
				(width 0.1524)
				(type default)
			)
			(layer "F.SilkS")
		)
		(fp_line
			(start -0.7874 0.4064)
			(end -0.7874 -0.4064)
			(stroke
				(width 0.1524)
				(type default)
			)
			(layer "F.SilkS")
		)
		(fp_line
			(start 0.7874 -0.4064)
			(end 0.7874 0.4064)
			(stroke
				(width 0.1524)
				(type default)
			)
			(layer "F.SilkS")
		)
		(fp_line
			(start 0.7874 0.4064)
			(end -0.7874 0.4064)
			(stroke
				(width 0.1524)
				(type default)
			)
			(layer "F.SilkS")
		)
		(fp_line
			(start -0.67945 -0.305054)
			(end -0.12065 -0.305054)
			(stroke
				(width 0.1)
				(type default)
			)
			(layer "F.Fab")
		)
		(fp_line
			(start -0.67945 0.3048)
			(end -0.67945 -0.305054)
			(stroke
				(width 0.1)
				(type default)
			)
			(layer "F.Fab")
		)
		(fp_line
			(start -0.12065 -0.305054)
			(end -0.12065 -0.2794)
			(stroke
				(width 0.1)
				(type default)
			)
			(layer "F.Fab")
		)
		(fp_line
			(start -0.12065 -0.2794)
			(end 0.12065 -0.2794)
			(stroke
				(width 0.1)
				(type default)
			)
			(layer "F.Fab")
		)
		(fp_line
			(start -0.12065 0.2794)
			(end -0.12065 0.3048)
			(stroke
				(width 0.1)
				(type default)
			)
			(layer "F.Fab")
		)
		(fp_line
			(start -0.12065 0.3048)
			(end -0.67945 0.3048)
			(stroke
				(width 0.1)
				(type default)
			)
			(layer "F.Fab")
		)
		(fp_line
			(start 0.120396 0.2794)
			(end -0.12065 0.2794)
			(stroke
				(width 0.1)
				(type default)
			)
			(layer "F.Fab")
		)
		(fp_line
			(start 0.120396 0.3048)
			(end 0.120396 0.2794)
			(stroke
				(width 0.1)
				(type default)
			)
			(layer "F.Fab")
		)
		(fp_line
			(start 0.12065 -0.3048)
			(end 0.67945 -0.3048)
			(stroke
				(width 0.1)
				(type default)
			)
			(layer "F.Fab")
		)
		(fp_line
			(start 0.12065 -0.2794)
			(end 0.12065 -0.3048)
			(stroke
				(width 0.1)
				(type default)
			)
			(layer "F.Fab")
		)
		(fp_line
			(start 0.67945 -0.3048)
			(end 0.67945 0.3048)
			(stroke
				(width 0.1)
				(type default)
			)
			(layer "F.Fab")
		)
		(fp_line
			(start 0.67945 0.3048)
			(end 0.120396 0.3048)
			(stroke
				(width 0.1)
				(type default)
			)
			(layer "F.Fab")
		)
		(pad "1" smd circle
			(at -0.40005 0)
			(size 0 0)
			(layers "F.Cu" "F.Mask" "F.Paste")
			(net "P3V3_MAX11617_VDD")
		)
		(pad "2" smd circle
			(at 0.40005 0)
			(size 0 0)
			(layers "F.Cu" "F.Mask" "F.Paste")
			(net "GND")
		)
	)
	(footprint ""
		(layer "F.Cu")
		(at 278.439626 -16.576548)
		(property "Reference" "C1824"
			(at 0 0 0)
			(layer "F.SilkS")
			(hide yes)
			(effects
				(font
					(size 1.27 1.27)
				)
			)
		)
		(property "Value" ""
			(at 0 0 0)
			(layer "F.Fab")
			(effects
				(font
					(size 1.27 1.27)
				)
			)
		)
		(duplicate_pad_numbers_are_jumpers no)
		(fp_line
			(start -0.7874 -0.4064)
			(end 0.7874 -0.4064)
			(stroke
				(width 0.1524)
				(type default)
			)
			(layer "F.SilkS")
		)
		(fp_line
			(start -0.7874 0.4064)
			(end -0.7874 -0.4064)
			(stroke
				(width 0.1524)
				(type default)
			)
			(layer "F.SilkS")
		)
		(fp_line
			(start 0.7874 -0.4064)
			(end 0.7874 0.4064)
			(stroke
				(width 0.1524)
				(type default)
			)
			(layer "F.SilkS")
		)
		(fp_line
			(start 0.7874 0.4064)
			(end -0.7874 0.4064)
			(stroke
				(width 0.1524)
				(type default)
			)
			(layer "F.SilkS")
		)
		(fp_line
			(start -0.67945 -0.305054)
			(end -0.12065 -0.305054)
			(stroke
				(width 0.1)
				(type default)
			)
			(layer "F.Fab")
		)
		(fp_line
			(start -0.67945 0.3048)
			(end -0.67945 -0.305054)
			(stroke
				(width 0.1)
				(type default)
			)
			(layer "F.Fab")
		)
		(fp_line
			(start -0.12065 -0.305054)
			(end -0.12065 -0.2794)
			(stroke
				(width 0.1)
				(type default)
			)
			(layer "F.Fab")
		)
		(fp_line
			(start -0.12065 -0.2794)
			(end 0.12065 -0.2794)
			(stroke
				(width 0.1)
				(type default)
			)
			(layer "F.Fab")
		)
		(fp_line
			(start -0.12065 0.2794)
			(end -0.12065 0.3048)
			(stroke
				(width 0.1)
				(type default)
			)
			(layer "F.Fab")
		)
		(fp_line
			(start -0.12065 0.3048)
			(end -0.67945 0.3048)
			(stroke
				(width 0.1)
				(type default)
			)
			(layer "F.Fab")
		)
		(fp_line
			(start 0.120396 0.2794)
			(end -0.12065 0.2794)
			(stroke
				(width 0.1)
				(type default)
			)
			(layer "F.Fab")
		)
		(fp_line
			(start 0.120396 0.3048)
			(end 0.120396 0.2794)
			(stroke
				(width 0.1)
				(type default)
			)
			(layer "F.Fab")
		)
		(fp_line
			(start 0.12065 -0.3048)
			(end 0.67945 -0.3048)
			(stroke
				(width 0.1)
				(type default)
			)
			(layer "F.Fab")
		)
		(fp_line
			(start 0.12065 -0.2794)
			(end 0.12065 -0.3048)
			(stroke
				(width 0.1)
				(type default)
			)
			(layer "F.Fab")
		)
		(fp_line
			(start 0.67945 -0.3048)
			(end 0.67945 0.3048)
			(stroke
				(width 0.1)
				(type default)
			)
			(layer "F.Fab")
		)
		(fp_line
			(start 0.67945 0.3048)
			(end 0.120396 0.3048)
			(stroke
				(width 0.1)
				(type default)
			)
			(layer "F.Fab")
		)
		(pad "1" smd circle
			(at -0.40005 0)
			(size 0 0)
			(layers "F.Cu" "F.Mask" "F.Paste")
			(net "P3V3_AUX")
		)
		(pad "2" smd circle
			(at 0.40005 0)
			(size 0 0)
			(layers "F.Cu" "F.Mask" "F.Paste")
			(net "GND")
		)
	)
	(footprint ""
		(layer "F.Cu")
		(at 413.520382 -30.893258)
		(property "Reference" "R3039"
			(at 0 0 0)
			(layer "F.SilkS")
			(hide yes)
			(effects
				(font
					(size 1.27 1.27)
				)
			)
		)
		(property "Value" ""
			(at 0 0 0)
			(layer "F.Fab")
			(effects
				(font
					(size 1.27 1.27)
				)
			)
		)
		(duplicate_pad_numbers_are_jumpers no)
		(fp_line
			(start -0.7874 -0.4064)
			(end 0.7874 -0.4064)
			(stroke
				(width 0.1524)
				(type default)
			)
			(layer "F.SilkS")
		)
		(fp_line
			(start -0.7874 0.4064)
			(end -0.7874 -0.4064)
			(stroke
				(width 0.1524)
				(type default)
			)
			(layer "F.SilkS")
		)
		(fp_line
			(start 0.7874 -0.4064)
			(end 0.7874 0.4064)
			(stroke
				(width 0.1524)
				(type default)
			)
			(layer "F.SilkS")
		)
		(fp_line
			(start 0.7874 0.4064)
			(end -0.7874 0.4064)
			(stroke
				(width 0.1524)
				(type default)
			)
			(layer "F.SilkS")
		)
		(fp_line
			(start -0.67945 -0.305054)
			(end -0.12065 -0.305054)
			(stroke
				(width 0.1)
				(type default)
			)
			(layer "F.Fab")
		)
		(fp_line
			(start -0.67945 0.3048)
			(end -0.67945 -0.305054)
			(stroke
				(width 0.1)
				(type default)
			)
			(layer "F.Fab")
		)
		(fp_line
			(start -0.12065 -0.305054)
			(end -0.12065 -0.2794)
			(stroke
				(width 0.1)
				(type default)
			)
			(layer "F.Fab")
		)
		(fp_line
			(start -0.12065 -0.2794)
			(end 0.12065 -0.2794)
			(stroke
				(width 0.1)
				(type default)
			)
			(layer "F.Fab")
		)
		(fp_line
			(start -0.12065 0.2794)
			(end -0.12065 0.3048)
			(stroke
				(width 0.1)
				(type default)
			)
			(layer "F.Fab")
		)
		(fp_line
			(start -0.12065 0.3048)
			(end -0.67945 0.3048)
			(stroke
				(width 0.1)
				(type default)
			)
			(layer "F.Fab")
		)
		(fp_line
			(start 0.120396 0.2794)
			(end -0.12065 0.2794)
			(stroke
				(width 0.1)
				(type default)
			)
			(layer "F.Fab")
		)
		(fp_line
			(start 0.120396 0.3048)
			(end 0.120396 0.2794)
			(stroke
				(width 0.1)
				(type default)
			)
			(layer "F.Fab")
		)
		(fp_line
			(start 0.12065 -0.3048)
			(end 0.67945 -0.3048)
			(stroke
				(width 0.1)
				(type default)
			)
			(layer "F.Fab")
		)
		(fp_line
			(start 0.12065 -0.2794)
			(end 0.12065 -0.3048)
			(stroke
				(width 0.1)
				(type default)
			)
			(layer "F.Fab")
		)
		(fp_line
			(start 0.67945 -0.3048)
			(end 0.67945 0.3048)
			(stroke
				(width 0.1)
				(type default)
			)
			(layer "F.Fab")
		)
		(fp_line
			(start 0.67945 0.3048)
			(end 0.120396 0.3048)
			(stroke
				(width 0.1)
				(type default)
			)
			(layer "F.Fab")
		)
		(pad "1" smd circle
			(at -0.40005 0)
			(size 0 0)
			(layers "F.Cu" "F.Mask" "F.Paste")
			(net "GND")
		)
		(pad "2" smd circle
			(at 0.40005 0)
			(size 0 0)
			(layers "F.Cu" "F.Mask" "F.Paste")
			(net "PD_ME_RCVR_N")
		)
	)
	(footprint ""
		(layer "F.Cu")
		(at 12.999974 -435.600094)
		(property "Reference" "H96"
			(at -5.463794 -5.055616 0)
			(unlocked yes)
			(layer "F.SilkS")
			(effects
				(font
					(size 0.7874 0.5842)
					(thickness 0.1524)
				)
				(justify left)
			)
		)
		(property "Value" ""
			(at 0 0 0)
			(layer "F.Fab")
			(effects
				(font
					(size 1.27 1.27)
				)
			)
		)
		(duplicate_pad_numbers_are_jumpers no)
		(pad "1" thru_hole circle
			(at 0 0)
			(size 10.0076 10.0076)
			(drill 5.6134)
			(layers "*.Cu" "*.Mask")
			(remove_unused_layers no)
			(net "GND")
			(clearance -1.9431)
		)
	)
	(footprint ""
		(layer "F.Cu")
		(at 117.53088 -101.793548 90)
		(property "Reference" "R4029"
			(at 0 0 90)
			(layer "F.SilkS")
			(hide yes)
			(effects
				(font
					(size 1.27 1.27)
				)
			)
		)
		(property "Value" ""
			(at 0 0 90)
			(layer "F.Fab")
			(effects
				(font
					(size 1.27 1.27)
				)
			)
		)
		(duplicate_pad_numbers_are_jumpers no)
		(fp_line
			(start 0.7874 -0.4064)
			(end 0.7874 0.4064)
			(stroke
				(width 0.1524)
				(type default)
			)
			(layer "F.SilkS")
		)
		(fp_line
			(start -0.7874 -0.4064)
			(end 0.7874 -0.4064)
			(stroke
				(width 0.1524)
				(type default)
			)
			(layer "F.SilkS")
		)
		(fp_line
			(start 0.7874 0.4064)
			(end -0.7874 0.4064)
			(stroke
				(width 0.1524)
				(type default)
			)
			(layer "F.SilkS")
		)
		(fp_line
			(start -0.7874 0.4064)
			(end -0.7874 -0.4064)
			(stroke
				(width 0.1524)
				(type default)
			)
			(layer "F.SilkS")
		)
		(fp_line
			(start -0.12065 -0.305054)
			(end -0.12065 -0.2794)
			(stroke
				(width 0.1)
				(type default)
			)
			(layer "F.Fab")
		)
		(fp_line
			(start -0.67945 -0.305054)
			(end -0.12065 -0.305054)
			(stroke
				(width 0.1)
				(type default)
			)
			(layer "F.Fab")
		)
		(fp_line
			(start 0.67945 -0.3048)
			(end 0.67945 0.3048)
			(stroke
				(width 0.1)
				(type default)
			)
			(layer "F.Fab")
		)
		(fp_line
			(start 0.12065 -0.3048)
			(end 0.67945 -0.3048)
			(stroke
				(width 0.1)
				(type default)
			)
			(layer "F.Fab")
		)
		(fp_line
			(start 0.12065 -0.2794)
			(end 0.12065 -0.3048)
			(stroke
				(width 0.1)
				(type default)
			)
			(layer "F.Fab")
		)
		(fp_line
			(start -0.12065 -0.2794)
			(end 0.12065 -0.2794)
			(stroke
				(width 0.1)
				(type default)
			)
			(layer "F.Fab")
		)
		(fp_line
			(start 0.120396 0.2794)
			(end -0.12065 0.2794)
			(stroke
				(width 0.1)
				(type default)
			)
			(layer "F.Fab")
		)
		(fp_line
			(start -0.12065 0.2794)
			(end -0.12065 0.3048)
			(stroke
				(width 0.1)
				(type default)
			)
			(layer "F.Fab")
		)
		(fp_line
			(start 0.67945 0.3048)
			(end 0.120396 0.3048)
			(stroke
				(width 0.1)
				(type default)
			)
			(layer "F.Fab")
		)
		(fp_line
			(start 0.120396 0.3048)
			(end 0.120396 0.2794)
			(stroke
				(width 0.1)
				(type default)
			)
			(layer "F.Fab")
		)
		(fp_line
			(start -0.12065 0.3048)
			(end -0.67945 0.3048)
			(stroke
				(width 0.1)
				(type default)
			)
			(layer "F.Fab")
		)
		(fp_line
			(start -0.67945 0.3048)
			(end -0.67945 -0.305054)
			(stroke
				(width 0.1)
				(type default)
			)
			(layer "F.Fab")
		)
		(pad "1" smd circle
			(at -0.40005 0 90)
			(size 0 0)
			(layers "F.Cu" "F.Mask" "F.Paste")
			(net "PD_CPU0_ERRS_DIR")
		)
		(pad "2" smd circle
			(at 0.40005 0 90)
			(size 0 0)
			(layers "F.Cu" "F.Mask" "F.Paste")
			(net "GND")
		)
	)
	(footprint ""
		(layer "F.Cu")
		(at 309.522622 -47.107348)
		(property "Reference" "R1456"
			(at 0 0 0)
			(layer "F.SilkS")
			(hide yes)
			(effects
				(font
					(size 1.27 1.27)
				)
			)
		)
		(property "Value" ""
			(at 0 0 0)
			(layer "F.Fab")
			(effects
				(font
					(size 1.27 1.27)
				)
			)
		)
		(duplicate_pad_numbers_are_jumpers no)
		(fp_line
			(start -0.7874 -0.4064)
			(end 0.7874 -0.4064)
			(stroke
				(width 0.1524)
				(type default)
			)
			(layer "F.SilkS")
		)
		(fp_line
			(start -0.7874 0.4064)
			(end -0.7874 -0.4064)
			(stroke
				(width 0.1524)
				(type default)
			)
			(layer "F.SilkS")
		)
		(fp_line
			(start 0.7874 -0.4064)
			(end 0.7874 0.4064)
			(stroke
				(width 0.1524)
				(type default)
			)
			(layer "F.SilkS")
		)
		(fp_line
			(start 0.7874 0.4064)
			(end -0.7874 0.4064)
			(stroke
				(width 0.1524)
				(type default)
			)
			(layer "F.SilkS")
		)
		(fp_line
			(start -0.67945 -0.305054)
			(end -0.12065 -0.305054)
			(stroke
				(width 0.1)
				(type default)
			)
			(layer "F.Fab")
		)
		(fp_line
			(start -0.67945 0.3048)
			(end -0.67945 -0.305054)
			(stroke
				(width 0.1)
				(type default)
			)
			(layer "F.Fab")
		)
		(fp_line
			(start -0.12065 -0.305054)
			(end -0.12065 -0.2794)
			(stroke
				(width 0.1)
				(type default)
			)
			(layer "F.Fab")
		)
		(fp_line
			(start -0.12065 -0.2794)
			(end 0.12065 -0.2794)
			(stroke
				(width 0.1)
				(type default)
			)
			(layer "F.Fab")
		)
		(fp_line
			(start -0.12065 0.2794)
			(end -0.12065 0.3048)
			(stroke
				(width 0.1)
				(type default)
			)
			(layer "F.Fab")
		)
		(fp_line
			(start -0.12065 0.3048)
			(end -0.67945 0.3048)
			(stroke
				(width 0.1)
				(type default)
			)
			(layer "F.Fab")
		)
		(fp_line
			(start 0.120396 0.2794)
			(end -0.12065 0.2794)
			(stroke
				(width 0.1)
				(type default)
			)
			(layer "F.Fab")
		)
		(fp_line
			(start 0.120396 0.3048)
			(end 0.120396 0.2794)
			(stroke
				(width 0.1)
				(type default)
			)
			(layer "F.Fab")
		)
		(fp_line
			(start 0.12065 -0.3048)
			(end 0.67945 -0.3048)
			(stroke
				(width 0.1)
				(type default)
			)
			(layer "F.Fab")
		)
		(fp_line
			(start 0.12065 -0.2794)
			(end 0.12065 -0.3048)
			(stroke
				(width 0.1)
				(type default)
			)
			(layer "F.Fab")
		)
		(fp_line
			(start 0.67945 -0.3048)
			(end 0.67945 0.3048)
			(stroke
				(width 0.1)
				(type default)
			)
			(layer "F.Fab")
		)
		(fp_line
			(start 0.67945 0.3048)
			(end 0.120396 0.3048)
			(stroke
				(width 0.1)
				(type default)
			)
			(layer "F.Fab")
		)
		(pad "1" smd circle
			(at -0.40005 0)
			(size 0 0)
			(layers "F.Cu" "F.Mask" "F.Paste")
			(net "FM_CPU_RMCA_CATERR_DLY_LVT3_R_N")
		)
		(pad "2" smd circle
			(at 0.40005 0)
			(size 0 0)
			(layers "F.Cu" "F.Mask" "F.Paste")
			(net "FM_CPU_RMCA_CATERR_DLY_N")
		)
	)
)
